(kicad_pcb
	(version 20260206)
	(generator "pcbnew")
	(generator_version "10.0")
	(general
		(thickness 1.6)
		(legacy_teardrops no)
	)
	(paper "A4")
	(title_block
		(title "03242023_DA0F0TMBIJ0_F0T_Motherboard_J_brd_V01_OCP.brd")
		(comment 1 "Grand Teton / footprints 1960-1966 of 6105")
	)
	(layers
		(0 "F.Cu" signal "TOP")
		(4 "In1.Cu" signal "GND")
		(6 "In2.Cu" signal "IN1")
		(8 "In3.Cu" signal "GND1")
		(10 "In4.Cu" signal "IN2")
		(12 "In5.Cu" signal "GND2")
		(14 "In6.Cu" signal "IN3")
		(16 "In7.Cu" signal "GND3")
		(18 "In8.Cu" signal "VCC")
		(20 "In9.Cu" signal "VCC1")
		(22 "In10.Cu" signal "GND4")
		(24 "In11.Cu" signal "IN4")
		(26 "In12.Cu" signal "GND5")
		(28 "In13.Cu" signal "IN5")
		(30 "In14.Cu" signal "GND6")
		(32 "In15.Cu" signal "IN6")
		(34 "In16.Cu" signal "GND7")
		(2 "B.Cu" signal "BOTTOM")
		(9 "F.Adhes" user "F.Adhesive")
		(11 "B.Adhes" user "B.Adhesive")
		(13 "F.Paste" user "Package Geometry/Pastemask Top")
		(15 "B.Paste" user "Package Geometry/Pastemask Bottom")
		(5 "F.SilkS" user "Ref Des/Silkscreen Top")
		(7 "B.SilkS" user "Ref Des/Silkscreen Bottom")
		(1 "F.Mask" user "Board Geometry/Soldermask Top")
		(3 "B.Mask" user "Board Geometry/Soldermask Bottom")
		(17 "Dwgs.User" user "User.Drawings")
		(19 "Cmts.User" user "User.Comments")
		(21 "Eco1.User" user "User.Eco1")
		(23 "Eco2.User" user "User.Eco2")
		(25 "Edge.Cuts" user "Board Geometry/Outline")
		(27 "Margin" user)
		(31 "F.CrtYd" user "Package Geometry/Place Bound Top")
		(29 "B.CrtYd" user "Package Geometry/Place Bound Bottom")
		(35 "F.Fab" user "Ref Des/Assembly Top")
		(33 "B.Fab" user "Ref Des/Assembly Bottom")
	)
	(footprint ""
		(layer "F.Cu")
		(at 379.319536 -105.483152 90)
		(property "Reference" "R1369"
			(at 0 0 90)
			(layer "F.SilkS")
			(hide yes)
			(effects
				(font
					(size 1.27 1.27)
				)
			)
		)
		(property "Value" ""
			(at 0 0 90)
			(layer "F.Fab")
			(effects
				(font
					(size 1.27 1.27)
				)
			)
		)
		(duplicate_pad_numbers_are_jumpers no)
		(fp_line
			(start 0.7874 -0.4064)
			(end 0.7874 0.4064)
			(stroke
				(width 0.1524)
				(type default)
			)
			(layer "F.SilkS")
		)
		(fp_line
			(start -0.7874 -0.4064)
			(end 0.7874 -0.4064)
			(stroke
				(width 0.1524)
				(type default)
			)
			(layer "F.SilkS")
		)
		(fp_line
			(start 0.7874 0.4064)
			(end -0.7874 0.4064)
			(stroke
				(width 0.1524)
				(type default)
			)
			(layer "F.SilkS")
		)
		(fp_line
			(start -0.7874 0.4064)
			(end -0.7874 -0.4064)
			(stroke
				(width 0.1524)
				(type default)
			)
			(layer "F.SilkS")
		)
		(fp_line
			(start -0.12065 -0.305054)
			(end -0.12065 -0.2794)
			(stroke
				(width 0.1)
				(type default)
			)
			(layer "F.Fab")
		)
		(fp_line
			(start -0.67945 -0.305054)
			(end -0.12065 -0.305054)
			(stroke
				(width 0.1)
				(type default)
			)
			(layer "F.Fab")
		)
		(fp_line
			(start 0.67945 -0.3048)
			(end 0.67945 0.3048)
			(stroke
				(width 0.1)
				(type default)
			)
			(layer "F.Fab")
		)
		(fp_line
			(start 0.12065 -0.3048)
			(end 0.67945 -0.3048)
			(stroke
				(width 0.1)
				(type default)
			)
			(layer "F.Fab")
		)
		(fp_line
			(start 0.12065 -0.2794)
			(end 0.12065 -0.3048)
			(stroke
				(width 0.1)
				(type default)
			)
			(layer "F.Fab")
		)
		(fp_line
			(start -0.12065 -0.2794)
			(end 0.12065 -0.2794)
			(stroke
				(width 0.1)
				(type default)
			)
			(layer "F.Fab")
		)
		(fp_line
			(start 0.120396 0.2794)
			(end -0.12065 0.2794)
			(stroke
				(width 0.1)
				(type default)
			)
			(layer "F.Fab")
		)
		(fp_line
			(start -0.12065 0.2794)
			(end -0.12065 0.3048)
			(stroke
				(width 0.1)
				(type default)
			)
			(layer "F.Fab")
		)
		(fp_line
			(start 0.67945 0.3048)
			(end 0.120396 0.3048)
			(stroke
				(width 0.1)
				(type default)
			)
			(layer "F.Fab")
		)
		(fp_line
			(start 0.120396 0.3048)
			(end 0.120396 0.2794)
			(stroke
				(width 0.1)
				(type default)
			)
			(layer "F.Fab")
		)
		(fp_line
			(start -0.12065 0.3048)
			(end -0.67945 0.3048)
			(stroke
				(width 0.1)
				(type default)
			)
			(layer "F.Fab")
		)
		(fp_line
			(start -0.67945 0.3048)
			(end -0.67945 -0.305054)
			(stroke
				(width 0.1)
				(type default)
			)
			(layer "F.Fab")
		)
		(pad "1" smd circle
			(at -0.40005 0 90)
			(size 0 0)
			(layers "F.Cu" "F.Mask" "F.Paste")
			(net "PD_JTAG_DBP_B0")
		)
		(pad "2" smd circle
			(at 0.40005 0 90)
			(size 0 0)
			(layers "F.Cu" "F.Mask" "F.Paste")
			(net "GND")
		)
	)
	(footprint ""
		(layer "F.Cu")
		(at 459.22946 -420.632128)
		(property "Reference" ""
			(at 0 0 0)
			(layer "F.SilkS")
			(hide yes)
			(effects
				(font
					(size 1.27 1.27)
				)
			)
		)
		(property "Value" ""
			(at 0 0 0)
			(layer "F.Fab")
			(effects
				(font
					(size 1.27 1.27)
				)
			)
		)
		(duplicate_pad_numbers_are_jumpers no)
		(pad "1" smd circle
			(at 0 0)
			(size 0.9906 0.9906)
			(layers "F.Cu" "F.Mask" "F.Paste")
			(net "Net_285")
		)
		(zone
			(layer "F.Cu")
			(hatch none 0.5)
			(connect_pads
				(clearance 0)
			)
			(min_thickness 0.25)
			(keepout
				(tracks not_allowed)
				(vias allowed)
				(pads allowed)
				(copperpour not_allowed)
				(footprints allowed)
			)
			(placement
				(enabled no)
				(sheetname "")
			)
			(fill
				(thermal_gap 0.5)
				(thermal_bridge_width 0.5)
				(island_removal_mode 0)
			)
			(polygon
				(pts
					(arc
						(start 460.85506 -420.632128)
						(mid 457.60386 -420.632128)
						(end 460.85506 -420.632128)
					)
				)
			)
		)
	)
	(footprint ""
		(layer "F.Cu")
		(at 121.430034 -358.430576)
		(property "Reference" "PC1264"
			(at 0 0 0)
			(layer "F.SilkS")
			(hide yes)
			(effects
				(font
					(size 1.27 1.27)
				)
			)
		)
		(property "Value" ""
			(at 0 0 0)
			(layer "F.Fab")
			(effects
				(font
					(size 1.27 1.27)
				)
			)
		)
		(duplicate_pad_numbers_are_jumpers no)
		(fp_line
			(start -0.7874 -0.4064)
			(end 0.7874 -0.4064)
			(stroke
				(width 0.1524)
				(type default)
			)
			(layer "F.SilkS")
		)
		(fp_line
			(start -0.7874 0.4064)
			(end -0.7874 -0.4064)
			(stroke
				(width 0.1524)
				(type default)
			)
			(layer "F.SilkS")
		)
		(fp_line
			(start 0.7874 -0.4064)
			(end 0.7874 0.4064)
			(stroke
				(width 0.1524)
				(type default)
			)
			(layer "F.SilkS")
		)
		(fp_line
			(start 0.7874 0.4064)
			(end -0.7874 0.4064)
			(stroke
				(width 0.1524)
				(type default)
			)
			(layer "F.SilkS")
		)
		(fp_line
			(start -0.67945 -0.305054)
			(end -0.12065 -0.305054)
			(stroke
				(width 0.1)
				(type default)
			)
			(layer "F.Fab")
		)
		(fp_line
			(start -0.67945 0.3048)
			(end -0.67945 -0.305054)
			(stroke
				(width 0.1)
				(type default)
			)
			(layer "F.Fab")
		)
		(fp_line
			(start -0.12065 -0.305054)
			(end -0.12065 -0.2794)
			(stroke
				(width 0.1)
				(type default)
			)
			(layer "F.Fab")
		)
		(fp_line
			(start -0.12065 -0.2794)
			(end 0.12065 -0.2794)
			(stroke
				(width 0.1)
				(type default)
			)
			(layer "F.Fab")
		)
		(fp_line
			(start -0.12065 0.2794)
			(end -0.12065 0.3048)
			(stroke
				(width 0.1)
				(type default)
			)
			(layer "F.Fab")
		)
		(fp_line
			(start -0.12065 0.3048)
			(end -0.67945 0.3048)
			(stroke
				(width 0.1)
				(type default)
			)
			(layer "F.Fab")
		)
		(fp_line
			(start 0.120396 0.2794)
			(end -0.12065 0.2794)
			(stroke
				(width 0.1)
				(type default)
			)
			(layer "F.Fab")
		)
		(fp_line
			(start 0.120396 0.3048)
			(end 0.120396 0.2794)
			(stroke
				(width 0.1)
				(type default)
			)
			(layer "F.Fab")
		)
		(fp_line
			(start 0.12065 -0.3048)
			(end 0.67945 -0.3048)
			(stroke
				(width 0.1)
				(type default)
			)
			(layer "F.Fab")
		)
		(fp_line
			(start 0.12065 -0.2794)
			(end 0.12065 -0.3048)
			(stroke
				(width 0.1)
				(type default)
			)
			(layer "F.Fab")
		)
		(fp_line
			(start 0.67945 -0.3048)
			(end 0.67945 0.3048)
			(stroke
				(width 0.1)
				(type default)
			)
			(layer "F.Fab")
		)
		(fp_line
			(start 0.67945 0.3048)
			(end 0.120396 0.3048)
			(stroke
				(width 0.1)
				(type default)
			)
			(layer "F.Fab")
		)
		(pad "1" smd circle
			(at -0.40005 0)
			(size 0 0)
			(layers "F.Cu" "F.Mask" "F.Paste")
			(net "PVPP_HBM_CPU1_REF")
		)
		(pad "2" smd circle
			(at 0.40005 0)
			(size 0 0)
			(layers "F.Cu" "F.Mask" "F.Paste")
			(net "SH_PVPP_HBM_CPU1_N")
		)
	)
	(footprint ""
		(layer "F.Cu")
		(at 107.287314 -258.72694 90)
		(property "Reference" "C221"
			(at 0 0 90)
			(layer "F.SilkS")
			(hide yes)
			(effects
				(font
					(size 1.27 1.27)
				)
			)
		)
		(property "Value" ""
			(at 0 0 90)
			(layer "F.Fab")
			(effects
				(font
					(size 1.27 1.27)
				)
			)
		)
		(duplicate_pad_numbers_are_jumpers no)
		(fp_line
			(start 0.7874 -0.4064)
			(end 0.7874 0.4064)
			(stroke
				(width 0.1524)
				(type default)
			)
			(layer "F.SilkS")
		)
		(fp_line
			(start -0.7874 -0.4064)
			(end 0.7874 -0.4064)
			(stroke
				(width 0.1524)
				(type default)
			)
			(layer "F.SilkS")
		)
		(fp_line
			(start 0.7874 0.4064)
			(end -0.7874 0.4064)
			(stroke
				(width 0.1524)
				(type default)
			)
			(layer "F.SilkS")
		)
		(fp_line
			(start -0.7874 0.4064)
			(end -0.7874 -0.4064)
			(stroke
				(width 0.1524)
				(type default)
			)
			(layer "F.SilkS")
		)
		(fp_line
			(start -0.12065 -0.305054)
			(end -0.12065 -0.2794)
			(stroke
				(width 0.1)
				(type default)
			)
			(layer "F.Fab")
		)
		(fp_line
			(start -0.67945 -0.305054)
			(end -0.12065 -0.305054)
			(stroke
				(width 0.1)
				(type default)
			)
			(layer "F.Fab")
		)
		(fp_line
			(start 0.67945 -0.3048)
			(end 0.67945 0.3048)
			(stroke
				(width 0.1)
				(type default)
			)
			(layer "F.Fab")
		)
		(fp_line
			(start 0.12065 -0.3048)
			(end 0.67945 -0.3048)
			(stroke
				(width 0.1)
				(type default)
			)
			(layer "F.Fab")
		)
		(fp_line
			(start 0.12065 -0.2794)
			(end 0.12065 -0.3048)
			(stroke
				(width 0.1)
				(type default)
			)
			(layer "F.Fab")
		)
		(fp_line
			(start -0.12065 -0.2794)
			(end 0.12065 -0.2794)
			(stroke
				(width 0.1)
				(type default)
			)
			(layer "F.Fab")
		)
		(fp_line
			(start 0.120396 0.2794)
			(end -0.12065 0.2794)
			(stroke
				(width 0.1)
				(type default)
			)
			(layer "F.Fab")
		)
		(fp_line
			(start -0.12065 0.2794)
			(end -0.12065 0.3048)
			(stroke
				(width 0.1)
				(type default)
			)
			(layer "F.Fab")
		)
		(fp_line
			(start 0.67945 0.3048)
			(end 0.120396 0.3048)
			(stroke
				(width 0.1)
				(type default)
			)
			(layer "F.Fab")
		)
		(fp_line
			(start 0.120396 0.3048)
			(end 0.120396 0.2794)
			(stroke
				(width 0.1)
				(type default)
			)
			(layer "F.Fab")
		)
		(fp_line
			(start -0.12065 0.3048)
			(end -0.67945 0.3048)
			(stroke
				(width 0.1)
				(type default)
			)
			(layer "F.Fab")
		)
		(fp_line
			(start -0.67945 0.3048)
			(end -0.67945 -0.305054)
			(stroke
				(width 0.1)
				(type default)
			)
			(layer "F.Fab")
		)
		(pad "1" smd circle
			(at -0.40005 0 90)
			(size 0 0)
			(layers "F.Cu" "F.Mask" "F.Paste")
			(net "PVCCIN_CPU1")
		)
		(pad "2" smd circle
			(at 0.40005 0 90)
			(size 0 0)
			(layers "F.Cu" "F.Mask" "F.Paste")
			(net "GND")
		)
	)
	(footprint ""
		(layer "F.Cu")
		(at 439.295032 -25.084278 180)
		(property "Reference" "PC2158"
			(at 0 0 180)
			(layer "F.SilkS")
			(hide yes)
			(effects
				(font
					(size 1.27 1.27)
				)
			)
		)
		(property "Value" ""
			(at 0 0 180)
			(layer "F.Fab")
			(effects
				(font
					(size 1.27 1.27)
				)
			)
		)
		(duplicate_pad_numbers_are_jumpers no)
		(fp_line
			(start 1.2954 0.5842)
			(end -1.2954 0.5842)
			(stroke
				(width 0.1524)
				(type default)
			)
			(layer "F.SilkS")
		)
		(fp_line
			(start 1.2954 -0.5842)
			(end 1.2954 0.5842)
			(stroke
				(width 0.1524)
				(type default)
			)
			(layer "F.SilkS")
		)
		(fp_line
			(start 0 -0.5842)
			(end 0 0.5842)
			(stroke
				(width 0.1524)
				(type default)
			)
			(layer "F.SilkS")
		)
		(fp_line
			(start -1.2954 0.5842)
			(end -1.2954 -0.5842)
			(stroke
				(width 0.1524)
				(type default)
			)
			(layer "F.SilkS")
		)
		(fp_line
			(start -1.2954 -0.5842)
			(end 1.2954 -0.5842)
			(stroke
				(width 0.1524)
				(type default)
			)
			(layer "F.SilkS")
		)
		(fp_line
			(start 1.1938 0.4064)
			(end 0.8636 0.4064)
			(stroke
				(width 0.1)
				(type default)
			)
			(layer "F.Fab")
		)
		(fp_line
			(start 1.1938 -0.4064)
			(end 1.1938 0.4064)
			(stroke
				(width 0.1)
				(type default)
			)
			(layer "F.Fab")
		)
		(fp_line
			(start 0.8636 0.4572)
			(end -0.8636 0.4572)
			(stroke
				(width 0.1)
				(type default)
			)
			(layer "F.Fab")
		)
		(fp_line
			(start 0.8636 0.4064)
			(end 0.8636 0.4572)
			(stroke
				(width 0.1)
				(type default)
			)
			(layer "F.Fab")
		)
		(fp_line
			(start 0.8636 -0.4064)
			(end 1.1938 -0.4064)
			(stroke
				(width 0.1)
				(type default)
			)
			(layer "F.Fab")
		)
		(fp_line
			(start 0.8636 -0.4572)
			(end 0.8636 -0.4064)
			(stroke
				(width 0.1)
				(type default)
			)
			(layer "F.Fab")
		)
		(fp_line
			(start -0.8636 0.4572)
			(end -0.8636 0.4064)
			(stroke
				(width 0.1)
				(type default)
			)
			(layer "F.Fab")
		)
		(fp_line
			(start -0.8636 0.4064)
			(end -1.1938 0.4064)
			(stroke
				(width 0.1)
				(type default)
			)
			(layer "F.Fab")
		)
		(fp_line
			(start -0.8636 -0.4064)
			(end -0.8636 -0.4572)
			(stroke
				(width 0.1)
				(type default)
			)
			(layer "F.Fab")
		)
		(fp_line
			(start -0.8636 -0.4572)
			(end 0.8636 -0.4572)
			(stroke
				(width 0.1)
				(type default)
			)
			(layer "F.Fab")
		)
		(fp_line
			(start -1.1938 0.4064)
			(end -1.1938 -0.4064)
			(stroke
				(width 0.1)
				(type default)
			)
			(layer "F.Fab")
		)
		(fp_line
			(start -1.1938 -0.4064)
			(end -0.8636 -0.4064)
			(stroke
				(width 0.1)
				(type default)
			)
			(layer "F.Fab")
		)
		(pad "1" smd rect
			(at -0.7366 0 90)
			(size 0.7112 0.8128)
			(layers "F.Cu" "F.Mask" "F.Paste")
			(net "P12V_OCP_AVIN_PD_1")
		)
		(pad "2" smd rect
			(at 0.7366 0 90)
			(size 0.7112 0.8128)
			(layers "F.Cu" "F.Mask" "F.Paste")
			(net "GND")
		)
	)
	(footprint ""
		(layer "F.Cu")
		(at 184.976008 -398.651222 180)
		(property "Reference" "R2586"
			(at 0 0 180)
			(layer "F.SilkS")
			(hide yes)
			(effects
				(font
					(size 1.27 1.27)
				)
			)
		)
		(property "Value" ""
			(at 0 0 180)
			(layer "F.Fab")
			(effects
				(font
					(size 1.27 1.27)
				)
			)
		)
		(duplicate_pad_numbers_are_jumpers no)
		(fp_line
			(start 0.7874 0.4064)
			(end -0.7874 0.4064)
			(stroke
				(width 0.1524)
				(type default)
			)
			(layer "F.SilkS")
		)
		(fp_line
			(start 0.7874 -0.4064)
			(end 0.7874 0.4064)
			(stroke
				(width 0.1524)
				(type default)
			)
			(layer "F.SilkS")
		)
		(fp_line
			(start -0.7874 0.4064)
			(end -0.7874 -0.4064)
			(stroke
				(width 0.1524)
				(type default)
			)
			(layer "F.SilkS")
		)
		(fp_line
			(start -0.7874 -0.4064)
			(end 0.7874 -0.4064)
			(stroke
				(width 0.1524)
				(type default)
			)
			(layer "F.SilkS")
		)
		(fp_line
			(start 0.67945 0.3048)
			(end 0.120396 0.3048)
			(stroke
				(width 0.1)
				(type default)
			)
			(layer "F.Fab")
		)
		(fp_line
			(start 0.67945 -0.3048)
			(end 0.67945 0.3048)
			(stroke
				(width 0.1)
				(type default)
			)
			(layer "F.Fab")
		)
		(fp_line
			(start 0.12065 -0.2794)
			(end 0.12065 -0.3048)
			(stroke
				(width 0.1)
				(type default)
			)
			(layer "F.Fab")
		)
		(fp_line
			(start 0.12065 -0.3048)
			(end 0.67945 -0.3048)
			(stroke
				(width 0.1)
				(type default)
			)
			(layer "F.Fab")
		)
		(fp_line
			(start 0.120396 0.3048)
			(end 0.120396 0.2794)
			(stroke
				(width 0.1)
				(type default)
			)
			(layer "F.Fab")
		)
		(fp_line
			(start 0.120396 0.2794)
			(end -0.12065 0.2794)
			(stroke
				(width 0.1)
				(type default)
			)
			(layer "F.Fab")
		)
		(fp_line
			(start -0.12065 0.3048)
			(end -0.67945 0.3048)
			(stroke
				(width 0.1)
				(type default)
			)
			(layer "F.Fab")
		)
		(fp_line
			(start -0.12065 0.2794)
			(end -0.12065 0.3048)
			(stroke
				(width 0.1)
				(type default)
			)
			(layer "F.Fab")
		)
		(fp_line
			(start -0.12065 -0.2794)
			(end 0.12065 -0.2794)
			(stroke
				(width 0.1)
				(type default)
			)
			(layer "F.Fab")
		)
		(fp_line
			(start -0.12065 -0.305054)
			(end -0.12065 -0.2794)
			(stroke
				(width 0.1)
				(type default)
			)
			(layer "F.Fab")
		)
		(fp_line
			(start -0.67945 0.3048)
			(end -0.67945 -0.305054)
			(stroke
				(width 0.1)
				(type default)
			)
			(layer "F.Fab")
		)
		(fp_line
			(start -0.67945 -0.305054)
			(end -0.12065 -0.305054)
			(stroke
				(width 0.1)
				(type default)
			)
			(layer "F.Fab")
		)
		(pad "1" smd circle
			(at -0.40005 0 180)
			(size 0 0)
			(layers "F.Cu" "F.Mask" "F.Paste")
			(net "HSC_EN")
		)
		(pad "2" smd circle
			(at 0.40005 0 180)
			(size 0 0)
			(layers "F.Cu" "F.Mask" "F.Paste")
			(net "HSC_EN_R")
		)
	)
	(footprint ""
		(layer "F.Cu")
		(at 141.240256 -64.313308)
		(property "Reference" "R2282"
			(at 0 0 0)
			(layer "F.SilkS")
			(hide yes)
			(effects
				(font
					(size 1.27 1.27)
				)
			)
		)
		(property "Value" ""
			(at 0 0 0)
			(layer "F.Fab")
			(effects
				(font
					(size 1.27 1.27)
				)
			)
		)
		(duplicate_pad_numbers_are_jumpers no)
		(fp_line
			(start -0.7874 -0.4064)
			(end 0.7874 -0.4064)
			(stroke
				(width 0.1524)
				(type default)
			)
			(layer "F.SilkS")
		)
		(fp_line
			(start -0.7874 0.4064)
			(end -0.7874 -0.4064)
			(stroke
				(width 0.1524)
				(type default)
			)
			(layer "F.SilkS")
		)
		(fp_line
			(start 0.7874 -0.4064)
			(end 0.7874 0.4064)
			(stroke
				(width 0.1524)
				(type default)
			)
			(layer "F.SilkS")
		)
		(fp_line
			(start 0.7874 0.4064)
			(end -0.7874 0.4064)
			(stroke
				(width 0.1524)
				(type default)
			)
			(layer "F.SilkS")
		)
		(fp_line
			(start -0.67945 -0.305054)
			(end -0.12065 -0.305054)
			(stroke
				(width 0.1)
				(type default)
			)
			(layer "F.Fab")
		)
		(fp_line
			(start -0.67945 0.3048)
			(end -0.67945 -0.305054)
			(stroke
				(width 0.1)
				(type default)
			)
			(layer "F.Fab")
		)
		(fp_line
			(start -0.12065 -0.305054)
			(end -0.12065 -0.2794)
			(stroke
				(width 0.1)
				(type default)
			)
			(layer "F.Fab")
		)
		(fp_line
			(start -0.12065 -0.2794)
			(end 0.12065 -0.2794)
			(stroke
				(width 0.1)
				(type default)
			)
			(layer "F.Fab")
		)
		(fp_line
			(start -0.12065 0.2794)
			(end -0.12065 0.3048)
			(stroke
				(width 0.1)
				(type default)
			)
			(layer "F.Fab")
		)
		(fp_line
			(start -0.12065 0.3048)
			(end -0.67945 0.3048)
			(stroke
				(width 0.1)
				(type default)
			)
			(layer "F.Fab")
		)
		(fp_line
			(start 0.120396 0.2794)
			(end -0.12065 0.2794)
			(stroke
				(width 0.1)
				(type default)
			)
			(layer "F.Fab")
		)
		(fp_line
			(start 0.120396 0.3048)
			(end 0.120396 0.2794)
			(stroke
				(width 0.1)
				(type default)
			)
			(layer "F.Fab")
		)
		(fp_line
			(start 0.12065 -0.3048)
			(end 0.67945 -0.3048)
			(stroke
				(width 0.1)
				(type default)
			)
			(layer "F.Fab")
		)
		(fp_line
			(start 0.12065 -0.2794)
			(end 0.12065 -0.3048)
			(stroke
				(width 0.1)
				(type default)
			)
			(layer "F.Fab")
		)
		(fp_line
			(start 0.67945 -0.3048)
			(end 0.67945 0.3048)
			(stroke
				(width 0.1)
				(type default)
			)
			(layer "F.Fab")
		)
		(fp_line
			(start 0.67945 0.3048)
			(end 0.120396 0.3048)
			(stroke
				(width 0.1)
				(type default)
			)
			(layer "F.Fab")
		)
		(pad "1" smd circle
			(at -0.40005 0)
			(size 0 0)
			(layers "F.Cu" "F.Mask" "F.Paste")
			(net "P3V3_AUX")
		)
		(pad "2" smd circle
			(at 0.40005 0)
			(size 0 0)
			(layers "F.Cu" "F.Mask" "F.Paste")
			(net "E1S_0_PRSNT")
		)
	)
)
